(kicad_pcb
	(version 20260206)
	(generator "pcbnew")
	(generator_version "10.0")
	(general
		(thickness 1.6)
		(legacy_teardrops no)
	)
	(paper "A4")
	(title_block
		(title "v1-pdb — T6M_PDB_D_0927_0900.brd")
		(comment 1 "Open CloudServer (Microsoft) / footprints 96-102 of 321")
	)
	(layers
		(0 "F.Cu" signal "TOP")
		(4 "In1.Cu" signal "GND")
		(6 "In2.Cu" signal "IN1")
		(8 "In3.Cu" signal "VCC")
		(10 "In4.Cu" signal "VCC1")
		(12 "In5.Cu" signal "IN2")
		(14 "In6.Cu" signal "GND1")
		(2 "B.Cu" signal "BOTTOM")
		(9 "F.Adhes" user "F.Adhesive")
		(11 "B.Adhes" user "B.Adhesive")
		(13 "F.Paste" user "Package Geometry/Pastemask Top")
		(15 "B.Paste" user "Package Geometry/Pastemask Bottom")
		(5 "F.SilkS" user "Ref Des/Silkscreen Top")
		(7 "B.SilkS" user "Ref Des/Silkscreen Bottom")
		(1 "F.Mask" user "Board Geometry/Soldermask Top")
		(3 "B.Mask" user "Board Geometry/Soldermask Bottom")
		(17 "Dwgs.User" user "User.Drawings")
		(19 "Cmts.User" user "User.Comments")
		(21 "Eco1.User" user "User.Eco1")
		(23 "Eco2.User" user "User.Eco2")
		(25 "Edge.Cuts" user "Board Geometry/Outline")
		(27 "Margin" user)
		(31 "F.CrtYd" user "Package Geometry/Place Bound Top")
		(29 "B.CrtYd" user "Package Geometry/Place Bound Bottom")
		(35 "F.Fab" user "Ref Des/Assembly Top")
		(33 "B.Fab" user "Ref Des/Assembly Bottom")
	)
	(footprint ""
		(layer "F.Cu")
		(at 78.000098 -519.049762)
		(property "Reference" "H1"
			(at -5.872734 -7.468108 0)
			(unlocked yes)
			(layer "F.SilkS")
			(effects
				(font
					(size 0.7874 0.5842)
					(thickness 0.1524)
				)
				(justify left)
			)
		)
		(property "Value" ""
			(at 0 0 0)
			(layer "F.Fab")
			(effects
				(font
					(size 1.27 1.27)
				)
			)
		)
		(duplicate_pad_numbers_are_jumpers no)
		(fp_circle
			(center 0 0)
			(end 7.999984 0)
			(stroke
				(width 0.1524)
				(type default)
			)
			(fill no)
			(layer "F.SilkS")
		)
		(fp_circle
			(center 0 0)
			(end 14.7066 0)
			(stroke
				(width 0.1524)
				(type default)
			)
			(fill no)
			(layer "B.SilkS")
		)
		(fp_poly
			(pts
				(arc
					(start 5.0038 0)
					(mid -5.0038 0)
					(end 5.0038 0)
				)
			)
			(stroke
				(width 0)
				(type default)
			)
			(fill no)
			(layer "F.CrtYd")
		)
		(pad "" np_thru_hole circle
			(at 0 0)
			(size 4.0132 4.0132)
			(drill 4.0132)
			(layers "*.Cu" "*.Mask")
			(clearance 0.381)
			(thermal_gap 0.381)
		)
		(pad "2" thru_hole circle
			(at 0 -3.50012)
			(size 0.762 0.762)
			(drill 0.5588)
			(layers "*.Cu" "*.Mask")
			(remove_unused_layers no)
			(net "GND")
			(clearance 0.1524)
			(thermal_gap 0.1524)
		)
		(pad "3" thru_hole circle
			(at -2.500122 -2.500122)
			(size 0.762 0.762)
			(drill 0.5588)
			(layers "*.Cu" "*.Mask")
			(remove_unused_layers no)
			(net "GND")
			(clearance 0.1524)
			(thermal_gap 0.1524)
		)
		(pad "4" thru_hole circle
			(at -3.50012 0)
			(size 0.762 0.762)
			(drill 0.5588)
			(layers "*.Cu" "*.Mask")
			(remove_unused_layers no)
			(net "GND")
			(clearance 0.1524)
			(thermal_gap 0.1524)
		)
		(pad "5" thru_hole circle
			(at -2.500122 2.500122)
			(size 0.762 0.762)
			(drill 0.5588)
			(layers "*.Cu" "*.Mask")
			(remove_unused_layers no)
			(net "GND")
			(clearance 0.1524)
			(thermal_gap 0.1524)
		)
		(pad "6" thru_hole circle
			(at 0 3.50012)
			(size 0.762 0.762)
			(drill 0.5588)
			(layers "*.Cu" "*.Mask")
			(remove_unused_layers no)
			(net "GND")
			(clearance 0.1524)
			(thermal_gap 0.1524)
		)
		(pad "7" thru_hole circle
			(at 2.500122 2.500122)
			(size 0.762 0.762)
			(drill 0.5588)
			(layers "*.Cu" "*.Mask")
			(remove_unused_layers no)
			(net "GND")
			(clearance 0.1524)
			(thermal_gap 0.1524)
		)
		(pad "8" thru_hole circle
			(at 3.50012 0)
			(size 0.762 0.762)
			(drill 0.5588)
			(layers "*.Cu" "*.Mask")
			(remove_unused_layers no)
			(net "GND")
			(clearance 0.1524)
			(thermal_gap 0.1524)
		)
		(pad "9" thru_hole circle
			(at 2.500122 -2.500122)
			(size 0.762 0.762)
			(drill 0.5588)
			(layers "*.Cu" "*.Mask")
			(remove_unused_layers no)
			(net "GND")
			(clearance 0.1524)
			(thermal_gap 0.1524)
		)
		(zone
			(layer "F.Cu")
			(hatch none 0.5)
			(connect_pads
				(clearance 0)
			)
			(min_thickness 0.25)
			(keepout
				(tracks not_allowed)
				(vias allowed)
				(pads allowed)
				(copperpour not_allowed)
				(footprints allowed)
			)
			(placement
				(enabled no)
				(sheetname "")
			)
			(fill
				(thermal_gap 0.5)
				(thermal_bridge_width 0.5)
				(island_removal_mode 0)
			)
			(polygon
				(pts
					(arc
						(start 78.000098 -527.050762)
						(mid 69.999098 -519.049762)
						(end 78.000098 -511.048762)
					)
					(arc
						(start 78.000098 -511.048762)
						(mid 79.435198 -512.483862)
						(end 78.000098 -513.918962)
					)
					(arc
						(start 78.000098 -513.918962)
						(mid 72.869298 -519.049762)
						(end 78.000098 -524.180562)
					)
					(arc
						(start 78.000098 -524.180562)
						(mid 79.435198 -525.615662)
						(end 78.000098 -527.050762)
					)
				)
			)
		)
		(zone
			(layer "F.Cu")
			(hatch none 0.5)
			(connect_pads
				(clearance 0)
			)
			(min_thickness 0.25)
			(keepout
				(tracks not_allowed)
				(vias allowed)
				(pads allowed)
				(copperpour not_allowed)
				(footprints allowed)
			)
			(placement
				(enabled no)
				(sheetname "")
			)
			(fill
				(thermal_gap 0.5)
				(thermal_bridge_width 0.5)
				(island_removal_mode 0)
			)
			(polygon
				(pts
					(arc
						(start 78.000098 -527.050762)
						(mid 86.001098 -519.049762)
						(end 78.000098 -511.048762)
					)
					(arc
						(start 78.000098 -511.048762)
						(mid 76.564998 -512.483862)
						(end 78.000098 -513.918962)
					)
					(arc
						(start 78.000098 -513.918962)
						(mid 83.130898 -519.049762)
						(end 78.000098 -524.180562)
					)
					(arc
						(start 78.000098 -524.180562)
						(mid 76.564998 -525.615662)
						(end 78.000098 -527.050762)
					)
				)
			)
		)
		(zone
			(layers "F.Cu" "B.Cu" "In1.Cu" "In2.Cu" "In3.Cu" "In4.Cu" "In5.Cu" "In6.Cu")
			(hatch none 0.5)
			(connect_pads
				(clearance 0)
			)
			(min_thickness 0.25)
			(keepout
				(tracks not_allowed)
				(vias allowed)
				(pads allowed)
				(copperpour not_allowed)
				(footprints allowed)
			)
			(placement
				(enabled no)
				(sheetname "")
			)
			(fill
				(thermal_gap 0.5)
				(thermal_bridge_width 0.5)
				(island_removal_mode 0)
			)
			(polygon
				(pts
					(arc
						(start 80.512158 -519.049762)
						(mid 75.488038 -519.049762)
						(end 80.512158 -519.049762)
					)
				)
			)
		)
	)
	(footprint ""
		(layer "F.Cu")
		(at 72.284082 -442.84646 90)
		(property "Reference" "C75"
			(at -3.89128 0.132334 90)
			(unlocked yes)
			(layer "F.SilkS")
			(effects
				(font
					(size 0.7874 0.5842)
					(thickness 0.1524)
				)
				(justify left)
			)
		)
		(property "Value" ""
			(at 0 0 90)
			(layer "F.Fab")
			(effects
				(font
					(size 1.27 1.27)
				)
			)
		)
		(duplicate_pad_numbers_are_jumpers no)
		(fp_line
			(start 0.7874 -0.4064)
			(end 0.7874 0.4064)
			(stroke
				(width 0.1524)
				(type default)
			)
			(layer "F.SilkS")
		)
		(fp_line
			(start -0.7874 -0.4064)
			(end 0.7874 -0.4064)
			(stroke
				(width 0.1524)
				(type default)
			)
			(layer "F.SilkS")
		)
		(fp_line
			(start 0 0.381)
			(end 0 -0.381)
			(stroke
				(width 0.1524)
				(type default)
			)
			(layer "F.SilkS")
		)
		(fp_line
			(start 0.7874 0.4064)
			(end -0.7874 0.4064)
			(stroke
				(width 0.1524)
				(type default)
			)
			(layer "F.SilkS")
		)
		(fp_line
			(start -0.7874 0.4064)
			(end -0.7874 -0.4064)
			(stroke
				(width 0.1524)
				(type default)
			)
			(layer "F.SilkS")
		)
		(fp_poly
			(pts
				(xy -0.5334 0.254) (xy -0.635 0.254) (xy -0.635 0.2286) (xy -0.635 -0.254) (xy -0.5334 -0.254) (xy -0.5334 -0.2794)
				(xy 0.5334 -0.2794) (xy 0.5334 -0.254) (xy 0.635 -0.254) (xy 0.635 0.254) (xy 0.5334 0.254) (xy 0.5334 0.2794)
				(xy -0.508 0.2794) (xy -0.5334 0.2794)
			)
			(stroke
				(width 0)
				(type default)
			)
			(fill no)
			(layer "F.CrtYd")
		)
		(pad "1" smd rect
			(at 0.40005 0 90)
			(size 0.4572 0.508)
			(layers "F.Cu" "F.Mask" "F.Paste")
			(net "P12V")
		)
		(pad "2" smd rect
			(at -0.40005 0 90)
			(size 0.4572 0.508)
			(layers "F.Cu" "F.Mask" "F.Paste")
			(net "GND")
		)
	)
	(footprint ""
		(layer "F.Cu")
		(at 39.459154 -111.174022 -90)
		(property "Reference" "R90"
			(at -1.104392 -0.0254 90)
			(unlocked yes)
			(layer "F.SilkS")
			(effects
				(font
					(size 0.7874 0.5842)
					(thickness 0.1524)
				)
				(justify left)
			)
		)
		(property "Value" ""
			(at 0 0 270)
			(layer "F.Fab")
			(effects
				(font
					(size 1.27 1.27)
				)
			)
		)
		(duplicate_pad_numbers_are_jumpers no)
		(fp_line
			(start -0.7874 0.4064)
			(end -0.7874 -0.4064)
			(stroke
				(width 0.1524)
				(type default)
			)
			(layer "F.SilkS")
		)
		(fp_line
			(start 0.7874 0.4064)
			(end -0.7874 0.4064)
			(stroke
				(width 0.1524)
				(type default)
			)
			(layer "F.SilkS")
		)
		(fp_line
			(start -0.7874 -0.4064)
			(end 0.7874 -0.4064)
			(stroke
				(width 0.1524)
				(type default)
			)
			(layer "F.SilkS")
		)
		(fp_line
			(start 0.7874 -0.4064)
			(end 0.7874 0.4064)
			(stroke
				(width 0.1524)
				(type default)
			)
			(layer "F.SilkS")
		)
		(fp_poly
			(pts
				(xy -0.508 0.2794) (xy -0.508 0.2286) (xy -0.635 0.2286) (xy -0.635 -0.254) (xy -0.5334 -0.254)
				(xy -0.5334 -0.2794) (xy 0.5334 -0.2794) (xy 0.5334 -0.254) (xy 0.635 -0.254) (xy 0.635 0.254) (xy 0.5334 0.254)
				(xy 0.5334 0.2794)
			)
			(stroke
				(width 0)
				(type default)
			)
			(fill no)
			(layer "F.CrtYd")
		)
		(pad "1" smd rect
			(at 0.40005 0 270)
			(size 0.4572 0.508)
			(layers "F.Cu" "F.Mask" "F.Paste")
			(net "PSU2_REMOTE_P")
		)
		(pad "2" smd rect
			(at -0.40005 0 270)
			(size 0.4572 0.508)
			(layers "F.Cu" "F.Mask" "F.Paste")
			(net "PSU2_REMOTE_R_P")
		)
	)
	(footprint ""
		(layer "F.Cu")
		(at 72.928734 -487.29138 90)
		(property "Reference" "C81"
			(at -4.217416 0.323088 90)
			(unlocked yes)
			(layer "F.SilkS")
			(effects
				(font
					(size 0.7874 0.5842)
					(thickness 0.1524)
				)
				(justify left)
			)
		)
		(property "Value" ""
			(at 0 0 90)
			(layer "F.Fab")
			(effects
				(font
					(size 1.27 1.27)
				)
			)
		)
		(duplicate_pad_numbers_are_jumpers no)
		(fp_line
			(start 0.7874 -0.4064)
			(end 0.7874 0.4064)
			(stroke
				(width 0.1524)
				(type default)
			)
			(layer "F.SilkS")
		)
		(fp_line
			(start -0.7874 -0.4064)
			(end 0.7874 -0.4064)
			(stroke
				(width 0.1524)
				(type default)
			)
			(layer "F.SilkS")
		)
		(fp_line
			(start 0 0.381)
			(end 0 -0.381)
			(stroke
				(width 0.1524)
				(type default)
			)
			(layer "F.SilkS")
		)
		(fp_line
			(start 0.7874 0.4064)
			(end -0.7874 0.4064)
			(stroke
				(width 0.1524)
				(type default)
			)
			(layer "F.SilkS")
		)
		(fp_line
			(start -0.7874 0.4064)
			(end -0.7874 -0.4064)
			(stroke
				(width 0.1524)
				(type default)
			)
			(layer "F.SilkS")
		)
		(fp_poly
			(pts
				(xy -0.5334 0.254) (xy -0.635 0.254) (xy -0.635 0.2286) (xy -0.635 -0.254) (xy -0.5334 -0.254) (xy -0.5334 -0.2794)
				(xy 0.5334 -0.2794) (xy 0.5334 -0.254) (xy 0.635 -0.254) (xy 0.635 0.254) (xy 0.5334 0.254) (xy 0.5334 0.2794)
				(xy -0.508 0.2794) (xy -0.5334 0.2794)
			)
			(stroke
				(width 0)
				(type default)
			)
			(fill no)
			(layer "F.CrtYd")
		)
		(pad "1" smd rect
			(at 0.40005 0 90)
			(size 0.4572 0.508)
			(layers "F.Cu" "F.Mask" "F.Paste")
			(net "P12V")
		)
		(pad "2" smd rect
			(at -0.40005 0 90)
			(size 0.4572 0.508)
			(layers "F.Cu" "F.Mask" "F.Paste")
			(net "GND")
		)
	)
	(footprint ""
		(layer "F.Cu")
		(at 91.399868 -286.709866)
		(property "Reference" "H21"
			(at -5.1308 -5.23113 0)
			(unlocked yes)
			(layer "F.SilkS")
			(effects
				(font
					(size 0.7874 0.5842)
					(thickness 0.1524)
				)
				(justify left)
			)
		)
		(property "Value" ""
			(at 0 0 0)
			(layer "F.Fab")
			(effects
				(font
					(size 1.27 1.27)
				)
			)
		)
		(duplicate_pad_numbers_are_jumpers no)
		(fp_circle
			(center 0 0)
			(end 4.826 0)
			(stroke
				(width 0.1524)
				(type default)
			)
			(fill no)
			(layer "F.SilkS")
		)
		(fp_circle
			(center 0 0)
			(end 4.826 0)
			(stroke
				(width 0.1524)
				(type default)
			)
			(fill no)
			(layer "B.SilkS")
		)
		(fp_poly
			(pts
				(arc
					(start 0 4.0132)
					(mid 0 -4.0132)
					(end 0 4.0132)
				)
			)
			(stroke
				(width 0)
				(type default)
			)
			(fill no)
			(layer "F.CrtYd")
		)
		(pad "" np_thru_hole circle
			(at 0 0)
			(size 8.001 8.001)
			(drill 8.001)
			(layers "*.Cu" "*.Mask")
			(clearance 0.381)
			(thermal_gap 0.381)
		)
		(zone
			(layers "F.Cu" "B.Cu" "In1.Cu" "In2.Cu" "In3.Cu" "In4.Cu" "In5.Cu" "In6.Cu")
			(hatch none 0.5)
			(connect_pads
				(clearance 0)
			)
			(min_thickness 0.25)
			(keepout
				(tracks not_allowed)
				(vias allowed)
				(pads allowed)
				(copperpour not_allowed)
				(footprints allowed)
			)
			(placement
				(enabled no)
				(sheetname "")
			)
			(fill
				(thermal_gap 0.5)
				(thermal_bridge_width 0.5)
				(island_removal_mode 0)
			)
			(polygon
				(pts
					(arc
						(start 91.399868 -282.188666)
						(mid 91.399868 -291.231066)
						(end 91.399868 -282.188666)
					)
				)
			)
		)
	)
	(footprint ""
		(layer "F.Cu")
		(at 16.599916 -473.69984)
		(property "Reference" "H8"
			(at -6.4516 -7.127748 0)
			(unlocked yes)
			(layer "F.SilkS")
			(effects
				(font
					(size 0.7874 0.5842)
					(thickness 0.1524)
				)
				(justify left)
			)
		)
		(property "Value" ""
			(at 0 0 0)
			(layer "F.Fab")
			(effects
				(font
					(size 1.27 1.27)
				)
			)
		)
		(duplicate_pad_numbers_are_jumpers no)
		(fp_circle
			(center 0 0)
			(end 7.999984 0)
			(stroke
				(width 0.1524)
				(type default)
			)
			(fill no)
			(layer "F.SilkS")
		)
		(fp_circle
			(center 0 0)
			(end 14.7066 0)
			(stroke
				(width 0.1524)
				(type default)
			)
			(fill no)
			(layer "B.SilkS")
		)
		(fp_poly
			(pts
				(arc
					(start 0 5.0038)
					(mid 0 -5.0038)
					(end 0 5.0038)
				)
			)
			(stroke
				(width 0)
				(type default)
			)
			(fill no)
			(layer "F.CrtYd")
		)
		(pad "" np_thru_hole circle
			(at 0 0)
			(size 4.0132 4.0132)
			(drill 4.0132)
			(layers "*.Cu" "*.Mask")
			(clearance 0.381)
			(thermal_gap 0.381)
		)
		(pad "2" thru_hole circle
			(at 0 -3.50012)
			(size 0.762 0.762)
			(drill 0.5588)
			(layers "*.Cu" "*.Mask")
			(remove_unused_layers no)
			(net "GND")
			(clearance 0.1524)
			(thermal_gap 0.1524)
		)
		(pad "3" thru_hole circle
			(at -2.500122 -2.500122)
			(size 0.762 0.762)
			(drill 0.5588)
			(layers "*.Cu" "*.Mask")
			(remove_unused_layers no)
			(net "GND")
			(clearance 0.1524)
			(thermal_gap 0.1524)
		)
		(pad "4" thru_hole circle
			(at -3.50012 0)
			(size 0.762 0.762)
			(drill 0.5588)
			(layers "*.Cu" "*.Mask")
			(remove_unused_layers no)
			(net "GND")
			(clearance 0.1524)
			(thermal_gap 0.1524)
		)
		(pad "5" thru_hole circle
			(at -2.500122 2.500122)
			(size 0.762 0.762)
			(drill 0.5588)
			(layers "*.Cu" "*.Mask")
			(remove_unused_layers no)
			(net "GND")
			(clearance 0.1524)
			(thermal_gap 0.1524)
		)
		(pad "6" thru_hole circle
			(at 0 3.50012)
			(size 0.762 0.762)
			(drill 0.5588)
			(layers "*.Cu" "*.Mask")
			(remove_unused_layers no)
			(net "GND")
			(clearance 0.1524)
			(thermal_gap 0.1524)
		)
		(pad "7" thru_hole circle
			(at 2.500122 2.500122)
			(size 0.762 0.762)
			(drill 0.5588)
			(layers "*.Cu" "*.Mask")
			(remove_unused_layers no)
			(net "GND")
			(clearance 0.1524)
			(thermal_gap 0.1524)
		)
		(pad "8" thru_hole circle
			(at 3.50012 0)
			(size 0.762 0.762)
			(drill 0.5588)
			(layers "*.Cu" "*.Mask")
			(remove_unused_layers no)
			(net "GND")
			(clearance 0.1524)
			(thermal_gap 0.1524)
		)
		(pad "9" thru_hole circle
			(at 2.500122 -2.500122)
			(size 0.762 0.762)
			(drill 0.5588)
			(layers "*.Cu" "*.Mask")
			(remove_unused_layers no)
			(net "GND")
			(clearance 0.1524)
			(thermal_gap 0.1524)
		)
		(zone
			(layer "F.Cu")
			(hatch none 0.5)
			(connect_pads
				(clearance 0)
			)
			(min_thickness 0.25)
			(keepout
				(tracks not_allowed)
				(vias allowed)
				(pads allowed)
				(copperpour not_allowed)
				(footprints allowed)
			)
			(placement
				(enabled no)
				(sheetname "")
			)
			(fill
				(thermal_gap 0.5)
				(thermal_bridge_width 0.5)
				(island_removal_mode 0)
			)
			(polygon
				(pts
					(arc
						(start 16.599916 -481.70084)
						(mid 8.598916 -473.69984)
						(end 16.599916 -465.69884)
					)
					(arc
						(start 16.599916 -465.69884)
						(mid 18.035016 -467.13394)
						(end 16.599916 -468.56904)
					)
					(arc
						(start 16.599916 -468.56904)
						(mid 11.469116 -473.69984)
						(end 16.599916 -478.83064)
					)
					(arc
						(start 16.599916 -478.83064)
						(mid 18.035016 -480.26574)
						(end 16.599916 -481.70084)
					)
				)
			)
		)
		(zone
			(layer "F.Cu")
			(hatch none 0.5)
			(connect_pads
				(clearance 0)
			)
			(min_thickness 0.25)
			(keepout
				(tracks not_allowed)
				(vias allowed)
				(pads allowed)
				(copperpour not_allowed)
				(footprints allowed)
			)
			(placement
				(enabled no)
				(sheetname "")
			)
			(fill
				(thermal_gap 0.5)
				(thermal_bridge_width 0.5)
				(island_removal_mode 0)
			)
			(polygon
				(pts
					(arc
						(start 16.599916 -481.70084)
						(mid 24.600916 -473.69984)
						(end 16.599916 -465.69884)
					)
					(arc
						(start 16.599916 -465.69884)
						(mid 15.164816 -467.13394)
						(end 16.599916 -468.56904)
					)
					(arc
						(start 16.599916 -468.56904)
						(mid 21.730716 -473.69984)
						(end 16.599916 -478.83064)
					)
					(arc
						(start 16.599916 -478.83064)
						(mid 15.164816 -480.26574)
						(end 16.599916 -481.70084)
					)
				)
			)
		)
		(zone
			(layers "F.Cu" "B.Cu" "In1.Cu" "In2.Cu" "In3.Cu" "In4.Cu" "In5.Cu" "In6.Cu")
			(hatch none 0.5)
			(connect_pads
				(clearance 0)
			)
			(min_thickness 0.25)
			(keepout
				(tracks not_allowed)
				(vias allowed)
				(pads allowed)
				(copperpour not_allowed)
				(footprints allowed)
			)
			(placement
				(enabled no)
				(sheetname "")
			)
			(fill
				(thermal_gap 0.5)
				(thermal_bridge_width 0.5)
				(island_removal_mode 0)
			)
			(polygon
				(pts
					(arc
						(start 16.599916 -471.18778)
						(mid 16.599916 -476.2119)
						(end 16.599916 -471.18778)
					)
				)
			)
		)
	)
	(footprint ""
		(layer "F.Cu")
		(at 71.810118 -487.29138 90)
		(property "Reference" "C82"
			(at -4.162806 0.225044 90)
			(unlocked yes)
			(layer "F.SilkS")
			(effects
				(font
					(size 0.7874 0.5842)
					(thickness 0.1524)
				)
				(justify left)
			)
		)
		(property "Value" ""
			(at 0 0 90)
			(layer "F.Fab")
			(effects
				(font
					(size 1.27 1.27)
				)
			)
		)
		(duplicate_pad_numbers_are_jumpers no)
		(fp_line
			(start 0.7874 -0.4064)
			(end 0.7874 0.4064)
			(stroke
				(width 0.1524)
				(type default)
			)
			(layer "F.SilkS")
		)
		(fp_line
			(start -0.7874 -0.4064)
			(end 0.7874 -0.4064)
			(stroke
				(width 0.1524)
				(type default)
			)
			(layer "F.SilkS")
		)
		(fp_line
			(start 0 0.381)
			(end 0 -0.381)
			(stroke
				(width 0.1524)
				(type default)
			)
			(layer "F.SilkS")
		)
		(fp_line
			(start 0.7874 0.4064)
			(end -0.7874 0.4064)
			(stroke
				(width 0.1524)
				(type default)
			)
			(layer "F.SilkS")
		)
		(fp_line
			(start -0.7874 0.4064)
			(end -0.7874 -0.4064)
			(stroke
				(width 0.1524)
				(type default)
			)
			(layer "F.SilkS")
		)
		(fp_poly
			(pts
				(xy -0.5334 0.254) (xy -0.635 0.254) (xy -0.635 0.2286) (xy -0.635 -0.254) (xy -0.5334 -0.254) (xy -0.5334 -0.2794)
				(xy 0.5334 -0.2794) (xy 0.5334 -0.254) (xy 0.635 -0.254) (xy 0.635 0.254) (xy 0.5334 0.254) (xy 0.5334 0.2794)
				(xy -0.508 0.2794) (xy -0.5334 0.2794)
			)
			(stroke
				(width 0)
				(type default)
			)
			(fill no)
			(layer "F.CrtYd")
		)
		(pad "1" smd rect
			(at 0.40005 0 90)
			(size 0.4572 0.508)
			(layers "F.Cu" "F.Mask" "F.Paste")
			(net "P12V")
		)
		(pad "2" smd rect
			(at -0.40005 0 90)
			(size 0.4572 0.508)
			(layers "F.Cu" "F.Mask" "F.Paste")
			(net "GND")
		)
	)
)
